# BASEBOARD_FAB2 (Tioga Pass) — schematic netlist excerpt (pin names and nets, part order shuffled) for the footprints in the layout excerpt that follows; sources: Cadence DE-HDL packaged netlist, KiCad conversion of Wiwynn_Tioga_Pass_MB.brd

U6W3  AT24C64  IC  pkg SOICLF  page 247
  A0  = PU_ID_EEPROM_A0
  A1  = GND
  A2  = GND
  SDA  = SMB_HOST_STBY_LVC3_SDA_R3
  SCL  = SMB_HOST_STBY_LVC3_SCL_R3
  WP  = PD_ID_EEPROM_WP

C3M2  CAP  0.22UF 16V 10% X7R  pkg 0402  page 105 : A = P3E_CPU0_PE1_PCH_R_RXP<15> ; B = P3E_CPU0_PE1_PCH_RXP<15>

(kicad_pcb
	(version 20260206)
	(generator "pcbnew")
	(generator_version "10.0")
	(general
		(thickness 1.6)
		(legacy_teardrops no)
	)
	(paper "A4")
	(title_block
		(title "Wiwynn_Tioga_Pass_MB.brd")
		(comment 1 "Tioga Pass / footprints 3495-3496 of 4770")
	)
	(layers
		(0 "F.Cu" signal "TOP")
		(4 "In1.Cu" signal "L2GND")
		(6 "In2.Cu" signal "L3")
		(8 "In3.Cu" signal "L4GND")
		(10 "In4.Cu" signal "L5")
		(12 "In5.Cu" signal "L6GND")
		(14 "In6.Cu" signal "L7VCC")
		(16 "In7.Cu" signal "L8VCC")
		(18 "In8.Cu" signal "L9GND")
		(20 "In9.Cu" signal "L10")
		(22 "In10.Cu" signal "L11GND")
		(24 "In11.Cu" signal "L12")
		(26 "In12.Cu" signal "L13GND")
		(2 "B.Cu" signal "BOTTOM")
		(9 "F.Adhes" user "F.Adhesive")
		(11 "B.Adhes" user "B.Adhesive")
		(13 "F.Paste" user "Package Geometry/Pastemask Top")
		(15 "B.Paste" user "Package Geometry/Pastemask Bottom")
		(5 "F.SilkS" user "Ref Des/Silkscreen Top")
		(7 "B.SilkS" user "Ref Des/Silkscreen Bottom")
		(1 "F.Mask" user "Board Geometry/Soldermask Top")
		(3 "B.Mask" user "Board Geometry/Soldermask Bottom")
		(17 "Dwgs.User" user "User.Drawings")
		(19 "Cmts.User" user "User.Comments")
		(21 "Eco1.User" user "User.Eco1")
		(23 "Eco2.User" user "User.Eco2")
		(25 "Edge.Cuts" user "Board Geometry/Outline")
		(27 "Margin" user)
		(31 "F.CrtYd" user "Package Geometry/Place Bound Top")
		(29 "B.CrtYd" user "Package Geometry/Place Bound Bottom")
		(35 "F.Fab" user "Ref Des/Assembly Top")
		(33 "B.Fab" user "Ref Des/Assembly Bottom")
	)
	(footprint ""
		(layer "B.Cu")
		(at 457.7842 -26.543)
		(property "Reference" "U6W3"
			(at -1.778 -1.46558 0)
			(unlocked yes)
			(layer "B.SilkS")
			(effects
				(font
					(size 0.4064 0.254)
					(thickness 0.1524)
				)
				(justify left mirror)
			)
		)
		(property "Value" ""
			(at 0 0 0)
			(layer "B.Fab")
			(effects
				(font
					(size 1.27 1.27)
				)
				(justify mirror)
			)
		)
		(duplicate_pad_numbers_are_jumpers no)
		(fp_line
			(start -4.191 -0.5969)
			(end -4.191 4.4069)
			(stroke
				(width 0.1524)
				(type default)
			)
			(layer "B.SilkS")
		)
		(fp_line
			(start -4.191 4.4069)
			(end -1.2954 4.4069)
			(stroke
				(width 0.1524)
				(type default)
			)
			(layer "B.SilkS")
		)
		(fp_line
			(start -3.3782 0.6731)
			(end -3.3782 -0.5842)
			(stroke
				(width 0.1524)
				(type default)
			)
			(layer "B.SilkS")
		)
		(fp_line
			(start -2.1082 -0.5842)
			(end -2.1082 0.6731)
			(stroke
				(width 0.1524)
				(type default)
			)
			(layer "B.SilkS")
		)
		(fp_line
			(start -2.1082 0.6731)
			(end -3.3782 0.6731)
			(stroke
				(width 0.1524)
				(type default)
			)
			(layer "B.SilkS")
		)
		(fp_line
			(start -1.2954 -0.5969)
			(end -4.191 -0.5969)
			(stroke
				(width 0.1524)
				(type default)
			)
			(layer "B.SilkS")
		)
		(fp_line
			(start -1.2954 4.4069)
			(end -1.2954 -0.5969)
			(stroke
				(width 0.1524)
				(type default)
			)
			(layer "B.SilkS")
		)
		(fp_circle
			(center 1.382014 -0.7112)
			(end 1.509014 -0.7112)
			(stroke
				(width 0.254)
				(type default)
			)
			(fill no)
			(layer "B.SilkS")
		)
		(fp_poly
			(pts
				(xy -0.7493 -0.5969) (xy -4.7371 -0.5969) (xy -4.7371 4.4069) (xy -0.7493 4.4069)
			)
			(stroke
				(width 0)
				(type default)
			)
			(fill no)
			(layer "B.CrtYd")
		)
		(fp_line
			(start -4.7371 -0.5969)
			(end -4.7371 4.4069)
			(stroke
				(width 0.1)
				(type default)
			)
			(layer "B.Fab")
		)
		(fp_line
			(start -4.7371 4.4069)
			(end -0.7493 4.4069)
			(stroke
				(width 0.1)
				(type default)
			)
			(layer "B.Fab")
		)
		(fp_line
			(start -3.3782 0.6731)
			(end -3.3782 -0.5842)
			(stroke
				(width 0.1)
				(type default)
			)
			(layer "B.Fab")
		)
		(fp_line
			(start -2.1082 -0.5842)
			(end -2.1082 0.6731)
			(stroke
				(width 0.1)
				(type default)
			)
			(layer "B.Fab")
		)
		(fp_line
			(start -2.1082 0.6731)
			(end -3.3782 0.6731)
			(stroke
				(width 0.1)
				(type default)
			)
			(layer "B.Fab")
		)
		(fp_line
			(start -0.7493 -0.5969)
			(end -4.7371 -0.5969)
			(stroke
				(width 0.1)
				(type default)
			)
			(layer "B.Fab")
		)
		(fp_line
			(start -0.7493 4.4069)
			(end -0.7493 -0.5969)
			(stroke
				(width 0.1)
				(type default)
			)
			(layer "B.Fab")
		)
		(fp_circle
			(center 1.382014 -0.7112)
			(end 1.509014 -0.7112)
			(stroke
				(width 0.254)
				(type default)
			)
			(fill no)
			(layer "B.Fab")
		)
		(pad "1" smd rect
			(at 0 0 180)
			(size 1.9304 0.635)
			(layers "B.Cu" "B.Mask" "B.Paste")
			(net "PU_ID_EEPROM_A0")
		)
		(pad "2" smd rect
			(at 0 1.27 180)
			(size 1.9304 0.635)
			(layers "B.Cu" "B.Mask" "B.Paste")
			(net "GND")
		)
		(pad "3" smd rect
			(at 0 2.54 180)
			(size 1.9304 0.635)
			(layers "B.Cu" "B.Mask" "B.Paste")
			(net "GND")
		)
		(pad "4" smd rect
			(at 0 3.81 180)
			(size 1.9304 0.635)
			(layers "B.Cu" "B.Mask" "B.Paste")
			(net "GND")
		)
		(pad "5" smd rect
			(at -5.4864 3.81 180)
			(size 1.9304 0.635)
			(layers "B.Cu" "B.Mask" "B.Paste")
			(net "SMB_HOST_STBY_LVC3_SDA_R3")
		)
		(pad "6" smd rect
			(at -5.4864 2.54 180)
			(size 1.9304 0.635)
			(layers "B.Cu" "B.Mask" "B.Paste")
			(net "SMB_HOST_STBY_LVC3_SCL_R3")
		)
		(pad "7" smd rect
			(at -5.4864 1.27 180)
			(size 1.9304 0.635)
			(layers "B.Cu" "B.Mask" "B.Paste")
			(net "PD_ID_EEPROM_WP")
		)
		(pad "8" smd rect
			(at -5.4864 0 180)
			(size 1.9304 0.635)
			(layers "B.Cu" "B.Mask" "B.Paste")
			(net "P3V3_STBY")
		)
	)
	(footprint ""
		(layer "B.Cu")
		(at 355.178614 -126.624842 -90)
		(property "Reference" "C3M2"
			(at 0 0 90)
			(layer "B.SilkS")
			(hide yes)
			(effects
				(font
					(size 1.27 1.27)
				)
				(justify mirror)
			)
		)
		(property "Value" ""
			(at 0 0 90)
			(layer "B.Fab")
			(effects
				(font
					(size 1.27 1.27)
				)
				(justify mirror)
			)
		)
		(duplicate_pad_numbers_are_jumpers no)
		(fp_poly
			(pts
				(xy -0.3048 -0.1016) (xy -0.3048 0.9906) (xy 0.3048 0.9906) (xy 0.3048 -0.1016)
			)
			(stroke
				(width 0)
				(type default)
			)
			(fill no)
			(layer "B.CrtYd")
		)
		(fp_line
			(start -0.3048 0.9906)
			(end -0.3048 -0.1016)
			(stroke
				(width 0.1)
				(type default)
			)
			(layer "B.Fab")
		)
		(fp_line
			(start 0.3048 0.9906)
			(end -0.3048 0.9906)
			(stroke
				(width 0.1)
				(type default)
			)
			(layer "B.Fab")
		)
		(fp_line
			(start -0.3048 -0.1016)
			(end 0.3048 -0.1016)
			(stroke
				(width 0.1)
				(type default)
			)
			(layer "B.Fab")
		)
		(fp_line
			(start 0.3048 -0.1016)
			(end 0.3048 0.9906)
			(stroke
				(width 0.1)
				(type default)
			)
			(layer "B.Fab")
		)
		(pad "1" smd rect
			(at 0 0 90)
			(size 0.508 0.508)
			(layers "B.Cu" "B.Mask" "B.Paste")
			(net "P3E_CPU0_PE1_PCH_R_RXP<15>")
		)
		(pad "2" smd rect
			(at 0 0.889 90)
			(size 0.508 0.508)
			(layers "B.Cu" "B.Mask" "B.Paste")
			(net "P3E_CPU0_PE1_PCH_RXP<15>")
		)
		(zone
			(layer "B.Cu")
			(hatch none 0.5)
			(connect_pads
				(clearance 0)
			)
			(min_thickness 0.25)
			(keepout
				(tracks not_allowed)
				(vias allowed)
				(pads allowed)
				(copperpour not_allowed)
				(footprints allowed)
			)
			(placement
				(enabled no)
				(sheetname "")
			)
			(fill
				(thermal_gap 0.5)
				(thermal_bridge_width 0.5)
				(island_removal_mode 0)
			)
			(polygon
				(pts
					(xy 354.543614 -126.370842) (xy 354.543614 -126.878842) (xy 354.924614 -126.878842) (xy 354.924614 -126.370842)
				)
			)
		)
		(zone
			(layer "B.Cu")
			(hatch none 0.5)
			(connect_pads
				(clearance 0)
			)
			(min_thickness 0.25)
			(keepout
				(tracks allowed)
				(vias not_allowed)
				(pads allowed)
				(copperpour not_allowed)
				(footprints allowed)
			)
			(placement
				(enabled no)
				(sheetname "")
			)
			(fill
				(thermal_gap 0.5)
				(thermal_bridge_width 0.5)
				(island_removal_mode 0)
			)
			(polygon
				(pts
					(xy 354.924614 -126.370842) (xy 354.924614 -126.878842) (xy 354.543614 -126.878842) (xy 354.543614 -126.370842)
				)
			)
		)
	)
)
